# BASEBOARD_FAB2 (Tioga Pass) — schematic netlist excerpt (pin names and nets, part order shuffled) for the footprints in the layout excerpt that follows; sources: Cadence DE-HDL packaged netlist, KiCad conversion of Wiwynn_Tioga_Pass_MB.brd

C1M3  CAP_A  1.0UF 6.3V 10% X6S  pkg 0402V  page 177 : A = P3V3 ; B = GND

L1M2  CHOKE_4PIN  90 OHM IND  pkg SMLF  page 176
  A1  = USB2_P01_DN
  A2  = USB2_P01_DP
  B1  = USB2_P01_ESD_DP
  B2  = USB2_P01_ESD_DN

(kicad_pcb
	(version 20260206)
	(generator "pcbnew")
	(generator_version "10.0")
	(general
		(thickness 1.6)
		(legacy_teardrops no)
	)
	(paper "A4")
	(title_block
		(title "Wiwynn_Tioga_Pass_MB.brd")
		(comment 1 "Tioga Pass / footprints 4533-4534 of 4770")
	)
	(layers
		(0 "F.Cu" signal "TOP")
		(4 "In1.Cu" signal "L2GND")
		(6 "In2.Cu" signal "L3")
		(8 "In3.Cu" signal "L4GND")
		(10 "In4.Cu" signal "L5")
		(12 "In5.Cu" signal "L6GND")
		(14 "In6.Cu" signal "L7VCC")
		(16 "In7.Cu" signal "L8VCC")
		(18 "In8.Cu" signal "L9GND")
		(20 "In9.Cu" signal "L10")
		(22 "In10.Cu" signal "L11GND")
		(24 "In11.Cu" signal "L12")
		(26 "In12.Cu" signal "L13GND")
		(2 "B.Cu" signal "BOTTOM")
		(9 "F.Adhes" user "F.Adhesive")
		(11 "B.Adhes" user "B.Adhesive")
		(13 "F.Paste" user "Package Geometry/Pastemask Top")
		(15 "B.Paste" user "Package Geometry/Pastemask Bottom")
		(5 "F.SilkS" user "Ref Des/Silkscreen Top")
		(7 "B.SilkS" user "Ref Des/Silkscreen Bottom")
		(1 "F.Mask" user "Board Geometry/Soldermask Top")
		(3 "B.Mask" user "Board Geometry/Soldermask Bottom")
		(17 "Dwgs.User" user "User.Drawings")
		(19 "Cmts.User" user "User.Comments")
		(21 "Eco1.User" user "User.Eco1")
		(23 "Eco2.User" user "User.Eco2")
		(25 "Edge.Cuts" user "Board Geometry/Outline")
		(27 "Margin" user)
		(31 "F.CrtYd" user "Package Geometry/Place Bound Top")
		(29 "B.CrtYd" user "Package Geometry/Place Bound Bottom")
		(35 "F.Fab" user "Ref Des/Assembly Top")
		(33 "B.Fab" user "Ref Des/Assembly Bottom")
	)
	(footprint ""
		(layer "B.Cu")
		(at 496.05438 -128.15062)
		(property "Reference" "C1M3"
			(at 0 0 0)
			(layer "B.SilkS")
			(hide yes)
			(effects
				(font
					(size 1.27 1.27)
				)
				(justify mirror)
			)
		)
		(property "Value" ""
			(at 0 0 0)
			(layer "B.Fab")
			(effects
				(font
					(size 1.27 1.27)
				)
				(justify mirror)
			)
		)
		(duplicate_pad_numbers_are_jumpers no)
		(fp_poly
			(pts
				(xy -0.3048 -0.1016) (xy -0.3048 0.9906) (xy 0.3048 0.9906) (xy 0.3048 -0.1016)
			)
			(stroke
				(width 0)
				(type default)
			)
			(fill no)
			(layer "B.CrtYd")
		)
		(fp_line
			(start -0.3048 -0.1016)
			(end 0.3048 -0.1016)
			(stroke
				(width 0.1)
				(type default)
			)
			(layer "B.Fab")
		)
		(fp_line
			(start -0.3048 0.9906)
			(end -0.3048 -0.1016)
			(stroke
				(width 0.1)
				(type default)
			)
			(layer "B.Fab")
		)
		(fp_line
			(start 0.3048 -0.1016)
			(end 0.3048 0.9906)
			(stroke
				(width 0.1)
				(type default)
			)
			(layer "B.Fab")
		)
		(fp_line
			(start 0.3048 0.9906)
			(end -0.3048 0.9906)
			(stroke
				(width 0.1)
				(type default)
			)
			(layer "B.Fab")
		)
		(pad "1" smd rect
			(at 0 0 180)
			(size 0.508 0.508)
			(layers "B.Cu" "B.Mask" "B.Paste")
			(net "P3V3")
		)
		(pad "2" smd rect
			(at 0 0.889 180)
			(size 0.508 0.508)
			(layers "B.Cu" "B.Mask" "B.Paste")
			(net "GND")
		)
		(zone
			(layer "B.Cu")
			(hatch none 0.5)
			(connect_pads
				(clearance 0)
			)
			(min_thickness 0.25)
			(keepout
				(tracks allowed)
				(vias not_allowed)
				(pads allowed)
				(copperpour not_allowed)
				(footprints allowed)
			)
			(placement
				(enabled no)
				(sheetname "")
			)
			(fill
				(thermal_gap 0.5)
				(thermal_bridge_width 0.5)
				(island_removal_mode 0)
			)
			(polygon
				(pts
					(xy 496.30838 -127.89662) (xy 495.80038 -127.89662) (xy 495.80038 -127.51562) (xy 496.30838 -127.51562)
				)
			)
		)
		(zone
			(layer "B.Cu")
			(hatch none 0.5)
			(connect_pads
				(clearance 0)
			)
			(min_thickness 0.25)
			(keepout
				(tracks not_allowed)
				(vias allowed)
				(pads allowed)
				(copperpour not_allowed)
				(footprints allowed)
			)
			(placement
				(enabled no)
				(sheetname "")
			)
			(fill
				(thermal_gap 0.5)
				(thermal_bridge_width 0.5)
				(island_removal_mode 0)
			)
			(polygon
				(pts
					(xy 496.30838 -127.51562) (xy 495.80038 -127.51562) (xy 495.80038 -127.89662) (xy 496.30838 -127.89662)
				)
			)
		)
	)
	(footprint ""
		(layer "B.Cu")
		(at 471.6653 -124.079 180)
		(property "Reference" "L1M2"
			(at -0.127 -1.07188 180)
			(unlocked yes)
			(layer "B.SilkS")
			(effects
				(font
					(size 0.4064 0.254)
					(thickness 0.1524)
				)
				(justify left mirror)
			)
		)
		(property "Value" ""
			(at 0 0 0)
			(layer "B.Fab")
			(effects
				(font
					(size 1.27 1.27)
				)
				(justify mirror)
			)
		)
		(duplicate_pad_numbers_are_jumpers no)
		(fp_rect
			(start 0.08382 1.09982)
			(end -2.11582 -0.29972)
			(stroke
				(width 0)
				(type default)
			)
			(fill no)
			(layer "B.CrtYd")
		)
		(fp_line
			(start 0.08382 1.09982)
			(end 0.08382 -0.29972)
			(stroke
				(width 0.1)
				(type default)
			)
			(layer "B.Fab")
		)
		(fp_line
			(start 0.08382 -0.29972)
			(end -2.11582 -0.29972)
			(stroke
				(width 0.1)
				(type default)
			)
			(layer "B.Fab")
		)
		(fp_line
			(start -2.11582 1.09982)
			(end 0.08382 1.09982)
			(stroke
				(width 0.1)
				(type default)
			)
			(layer "B.Fab")
		)
		(fp_line
			(start -2.11582 -0.29972)
			(end -2.11582 1.09982)
			(stroke
				(width 0.1)
				(type default)
			)
			(layer "B.Fab")
		)
		(pad "1" smd rect
			(at 0 0)
			(size 1.27 0.508)
			(layers "B.Cu" "B.Mask" "B.Paste")
			(net "USB2_P01_DN")
		)
		(pad "2" smd rect
			(at 0 0.8001)
			(size 1.27 0.508)
			(layers "B.Cu" "B.Mask" "B.Paste")
			(net "USB2_P01_DP")
		)
		(pad "3" smd rect
			(at -2.032 0.8001)
			(size 1.27 0.508)
			(layers "B.Cu" "B.Mask" "B.Paste")
			(net "USB2_P01_ESD_DP")
		)
		(pad "4" smd rect
			(at -2.032 0)
			(size 1.27 0.508)
			(layers "B.Cu" "B.Mask" "B.Paste")
			(net "USB2_P01_ESD_DN")
		)
		(zone
			(layer "B.Cu")
			(hatch none 0.5)
			(connect_pads
				(clearance 0)
			)
			(min_thickness 0.25)
			(keepout
				(tracks not_allowed)
				(vias allowed)
				(pads allowed)
				(copperpour not_allowed)
				(footprints allowed)
			)
			(placement
				(enabled no)
				(sheetname "")
			)
			(fill
				(thermal_gap 0.5)
				(thermal_bridge_width 0.5)
				(island_removal_mode 0)
			)
			(polygon
				(pts
					(xy 471.0303 -124.6251) (xy 471.0303 -124.333) (xy 472.3003 -124.333) (xy 472.3003 -124.6251)
				)
			)
		)
		(zone
			(layer "B.Cu")
			(hatch none 0.5)
			(connect_pads
				(clearance 0)
			)
			(min_thickness 0.25)
			(keepout
				(tracks not_allowed)
				(vias allowed)
				(pads allowed)
				(copperpour not_allowed)
				(footprints allowed)
			)
			(placement
				(enabled no)
				(sheetname "")
			)
			(fill
				(thermal_gap 0.5)
				(thermal_bridge_width 0.5)
				(island_removal_mode 0)
			)
			(polygon
				(pts
					(xy 472.3003 -125.1331) (xy 473.0623 -125.1331) (xy 473.0623 -123.825) (xy 472.3003 -123.825)
				)
			)
		)
		(zone
			(layer "B.Cu")
			(hatch none 0.5)
			(connect_pads
				(clearance 0)
			)
			(min_thickness 0.25)
			(keepout
				(tracks allowed)
				(vias not_allowed)
				(pads allowed)
				(copperpour not_allowed)
				(footprints allowed)
			)
			(placement
				(enabled no)
				(sheetname "")
			)
			(fill
				(thermal_gap 0.5)
				(thermal_bridge_width 0.5)
				(island_removal_mode 0)
			)
			(polygon
				(pts
					(xy 472.3003 -123.825) (xy 472.3003 -125.1331) (xy 473.0623 -125.1331) (xy 473.0623 -123.825)
				)
			)
		)
		(zone
			(layer "B.Cu")
			(hatch none 0.5)
			(connect_pads
				(clearance 0)
			)
			(min_thickness 0.25)
			(keepout
				(tracks not_allowed)
				(vias allowed)
				(pads allowed)
				(copperpour not_allowed)
				(footprints allowed)
			)
			(placement
				(enabled no)
				(sheetname "")
			)
			(fill
				(thermal_gap 0.5)
				(thermal_bridge_width 0.5)
				(island_removal_mode 0)
			)
			(polygon
				(pts
					(xy 473.0623 -124.6251) (xy 473.0623 -124.333) (xy 474.3323 -124.333) (xy 474.3323 -124.6251)
				)
			)
		)
	)
)
